(kicad_pcb
	(version 20260206)
	(generator "pcbnew")
	(generator_version "10.0")
	(general
		(thickness 1.6)
		(legacy_teardrops no)
	)
	(paper "A4")
	(title_block
		(title "03242023_DA0F0TMBIJ0_F0T_Motherboard_J_brd_V01_OCP.brd")
		(comment 1 "Grand Teton / footprints 1774-1779 of 6105")
	)
	(layers
		(0 "F.Cu" signal "TOP")
		(4 "In1.Cu" signal "GND")
		(6 "In2.Cu" signal "IN1")
		(8 "In3.Cu" signal "GND1")
		(10 "In4.Cu" signal "IN2")
		(12 "In5.Cu" signal "GND2")
		(14 "In6.Cu" signal "IN3")
		(16 "In7.Cu" signal "GND3")
		(18 "In8.Cu" signal "VCC")
		(20 "In9.Cu" signal "VCC1")
		(22 "In10.Cu" signal "GND4")
		(24 "In11.Cu" signal "IN4")
		(26 "In12.Cu" signal "GND5")
		(28 "In13.Cu" signal "IN5")
		(30 "In14.Cu" signal "GND6")
		(32 "In15.Cu" signal "IN6")
		(34 "In16.Cu" signal "GND7")
		(2 "B.Cu" signal "BOTTOM")
		(9 "F.Adhes" user "F.Adhesive")
		(11 "B.Adhes" user "B.Adhesive")
		(13 "F.Paste" user "Package Geometry/Pastemask Top")
		(15 "B.Paste" user "Package Geometry/Pastemask Bottom")
		(5 "F.SilkS" user "Ref Des/Silkscreen Top")
		(7 "B.SilkS" user "Ref Des/Silkscreen Bottom")
		(1 "F.Mask" user "Board Geometry/Soldermask Top")
		(3 "B.Mask" user "Board Geometry/Soldermask Bottom")
		(17 "Dwgs.User" user "User.Drawings")
		(19 "Cmts.User" user "User.Comments")
		(21 "Eco1.User" user "User.Eco1")
		(23 "Eco2.User" user "User.Eco2")
		(25 "Edge.Cuts" user "Board Geometry/Outline")
		(27 "Margin" user)
		(31 "F.CrtYd" user "Package Geometry/Place Bound Top")
		(29 "B.CrtYd" user "Package Geometry/Place Bound Bottom")
		(35 "F.Fab" user "Ref Des/Assembly Top")
		(33 "B.Fab" user "Ref Des/Assembly Bottom")
	)
	(footprint ""
		(layer "F.Cu")
		(at 166.196772 -129.036318 -90)
		(property "Reference" "Q37"
			(at 2.027428 -1.224788 0)
			(unlocked yes)
			(layer "F.SilkS")
			(effects
				(font
					(size 0.7874 0.5842)
					(thickness 0.1524)
				)
				(justify left)
			)
		)
		(property "Value" ""
			(at 0 0 270)
			(layer "F.Fab")
			(effects
				(font
					(size 1.27 1.27)
				)
			)
		)
		(duplicate_pad_numbers_are_jumpers no)
		(fp_line
			(start -1.332738 1.100074)
			(end -1.332738 -1.100074)
			(stroke
				(width 0.1524)
				(type default)
			)
			(layer "F.SilkS")
		)
		(fp_line
			(start 1.332738 1.100074)
			(end -1.332738 1.100074)
			(stroke
				(width 0.1524)
				(type default)
			)
			(layer "F.SilkS")
		)
		(fp_line
			(start 0 -0.541274)
			(end 0.4826 -1.100074)
			(stroke
				(width 0.1524)
				(type default)
			)
			(layer "F.SilkS")
		)
		(fp_line
			(start -1.332738 -1.100074)
			(end -0.4826 -1.100074)
			(stroke
				(width 0.1524)
				(type default)
			)
			(layer "F.SilkS")
		)
		(fp_line
			(start -0.4826 -1.100074)
			(end 0 -0.541274)
			(stroke
				(width 0.1524)
				(type default)
			)
			(layer "F.SilkS")
		)
		(fp_line
			(start 0.4826 -1.100074)
			(end 1.332738 -1.100074)
			(stroke
				(width 0.1524)
				(type default)
			)
			(layer "F.SilkS")
		)
		(fp_line
			(start 1.332738 -1.100074)
			(end 1.332738 1.100074)
			(stroke
				(width 0.1524)
				(type default)
			)
			(layer "F.SilkS")
		)
		(fp_poly
			(pts
				(xy -1.53416 -1.988312) (xy -1.323086 -1.232408) (xy -2.054606 -1.517142)
			)
			(stroke
				(width 0)
				(type default)
			)
			(fill yes)
			(layer "F.SilkS")
		)
		(fp_line
			(start -0.674878 1.100074)
			(end -0.674878 -1.100074)
			(stroke
				(width 0.1)
				(type default)
			)
			(layer "F.Fab")
		)
		(fp_line
			(start 0.674878 1.100074)
			(end -0.674878 1.100074)
			(stroke
				(width 0.1)
				(type default)
			)
			(layer "F.Fab")
		)
		(fp_line
			(start -0.674878 -1.100074)
			(end 0.674878 -1.100074)
			(stroke
				(width 0.1)
				(type default)
			)
			(layer "F.Fab")
		)
		(fp_line
			(start 0.674878 -1.100074)
			(end 0.674878 1.100074)
			(stroke
				(width 0.1)
				(type default)
			)
			(layer "F.Fab")
		)
		(fp_poly
			(pts
				(xy -2.2352 -0.298958) (xy -2.2352 -1.001014) (xy -1.533144 -0.649986)
			)
			(stroke
				(width 0)
				(type default)
			)
			(fill yes)
			(layer "F.Fab")
		)
		(pad "1" smd rect
			(at -0.94996 -0.649986)
			(size 0.4318 0.508)
			(layers "F.Cu" "F.Mask" "F.Paste")
			(net "GND")
		)
		(pad "2" smd rect
			(at -0.94996 0)
			(size 0.4318 0.508)
			(layers "F.Cu" "F.Mask" "F.Paste")
			(net "VR_P5V_EN")
		)
		(pad "3" smd rect
			(at -0.94996 0.649986)
			(size 0.4318 0.508)
			(layers "F.Cu" "F.Mask" "F.Paste")
			(net "VR_P5V_EN_D_R1")
		)
		(pad "4" smd rect
			(at 0.94996 0.649986)
			(size 0.4318 0.508)
			(layers "F.Cu" "F.Mask" "F.Paste")
			(net "GND")
		)
		(pad "5" smd rect
			(at 0.94996 0)
			(size 0.4318 0.508)
			(layers "F.Cu" "F.Mask" "F.Paste")
			(net "VR_P5V_EN_N")
		)
		(pad "6" smd rect
			(at 0.94996 -0.649986)
			(size 0.4318 0.508)
			(layers "F.Cu" "F.Mask" "F.Paste")
			(net "VR_P5V_EN_N")
		)
	)
	(footprint ""
		(layer "F.Cu")
		(at 157.02788 -116.296948)
		(property "Reference" "R3482"
			(at 0 0 0)
			(layer "F.SilkS")
			(hide yes)
			(effects
				(font
					(size 1.27 1.27)
				)
			)
		)
		(property "Value" ""
			(at 0 0 0)
			(layer "F.Fab")
			(effects
				(font
					(size 1.27 1.27)
				)
			)
		)
		(duplicate_pad_numbers_are_jumpers no)
		(fp_line
			(start -0.7874 -0.4064)
			(end 0.7874 -0.4064)
			(stroke
				(width 0.1524)
				(type default)
			)
			(layer "F.SilkS")
		)
		(fp_line
			(start -0.7874 0.4064)
			(end -0.7874 -0.4064)
			(stroke
				(width 0.1524)
				(type default)
			)
			(layer "F.SilkS")
		)
		(fp_line
			(start 0.7874 -0.4064)
			(end 0.7874 0.4064)
			(stroke
				(width 0.1524)
				(type default)
			)
			(layer "F.SilkS")
		)
		(fp_line
			(start 0.7874 0.4064)
			(end -0.7874 0.4064)
			(stroke
				(width 0.1524)
				(type default)
			)
			(layer "F.SilkS")
		)
		(fp_line
			(start -0.67945 -0.305054)
			(end -0.12065 -0.305054)
			(stroke
				(width 0.1)
				(type default)
			)
			(layer "F.Fab")
		)
		(fp_line
			(start -0.67945 0.3048)
			(end -0.67945 -0.305054)
			(stroke
				(width 0.1)
				(type default)
			)
			(layer "F.Fab")
		)
		(fp_line
			(start -0.12065 -0.305054)
			(end -0.12065 -0.2794)
			(stroke
				(width 0.1)
				(type default)
			)
			(layer "F.Fab")
		)
		(fp_line
			(start -0.12065 -0.2794)
			(end 0.12065 -0.2794)
			(stroke
				(width 0.1)
				(type default)
			)
			(layer "F.Fab")
		)
		(fp_line
			(start -0.12065 0.2794)
			(end -0.12065 0.3048)
			(stroke
				(width 0.1)
				(type default)
			)
			(layer "F.Fab")
		)
		(fp_line
			(start -0.12065 0.3048)
			(end -0.67945 0.3048)
			(stroke
				(width 0.1)
				(type default)
			)
			(layer "F.Fab")
		)
		(fp_line
			(start 0.120396 0.2794)
			(end -0.12065 0.2794)
			(stroke
				(width 0.1)
				(type default)
			)
			(layer "F.Fab")
		)
		(fp_line
			(start 0.120396 0.3048)
			(end 0.120396 0.2794)
			(stroke
				(width 0.1)
				(type default)
			)
			(layer "F.Fab")
		)
		(fp_line
			(start 0.12065 -0.3048)
			(end 0.67945 -0.3048)
			(stroke
				(width 0.1)
				(type default)
			)
			(layer "F.Fab")
		)
		(fp_line
			(start 0.12065 -0.2794)
			(end 0.12065 -0.3048)
			(stroke
				(width 0.1)
				(type default)
			)
			(layer "F.Fab")
		)
		(fp_line
			(start 0.67945 -0.3048)
			(end 0.67945 0.3048)
			(stroke
				(width 0.1)
				(type default)
			)
			(layer "F.Fab")
		)
		(fp_line
			(start 0.67945 0.3048)
			(end 0.120396 0.3048)
			(stroke
				(width 0.1)
				(type default)
			)
			(layer "F.Fab")
		)
		(pad "1" smd circle
			(at -0.40005 0)
			(size 0 0)
			(layers "F.Cu" "F.Mask" "F.Paste")
			(net "GPU_FPGA_BOOT_EN")
		)
		(pad "2" smd circle
			(at 0.40005 0)
			(size 0 0)
			(layers "F.Cu" "F.Mask" "F.Paste")
			(net "GPU_FPGA_BOOT_EN_R")
		)
	)
	(footprint ""
		(layer "F.Cu")
		(at 436.292244 -127.248158 -90)
		(property "Reference" "PR371"
			(at 0 0 270)
			(layer "F.SilkS")
			(hide yes)
			(effects
				(font
					(size 1.27 1.27)
				)
			)
		)
		(property "Value" ""
			(at 0 0 270)
			(layer "F.Fab")
			(effects
				(font
					(size 1.27 1.27)
				)
			)
		)
		(duplicate_pad_numbers_are_jumpers no)
		(fp_line
			(start -0.7874 0.4064)
			(end -0.7874 -0.4064)
			(stroke
				(width 0.1524)
				(type default)
			)
			(layer "F.SilkS")
		)
		(fp_line
			(start 0.7874 0.4064)
			(end -0.7874 0.4064)
			(stroke
				(width 0.1524)
				(type default)
			)
			(layer "F.SilkS")
		)
		(fp_line
			(start -0.7874 -0.4064)
			(end 0.7874 -0.4064)
			(stroke
				(width 0.1524)
				(type default)
			)
			(layer "F.SilkS")
		)
		(fp_line
			(start 0.7874 -0.4064)
			(end 0.7874 0.4064)
			(stroke
				(width 0.1524)
				(type default)
			)
			(layer "F.SilkS")
		)
		(fp_line
			(start -0.67945 0.3048)
			(end -0.67945 -0.305054)
			(stroke
				(width 0.1)
				(type default)
			)
			(layer "F.Fab")
		)
		(fp_line
			(start -0.12065 0.3048)
			(end -0.67945 0.3048)
			(stroke
				(width 0.1)
				(type default)
			)
			(layer "F.Fab")
		)
		(fp_line
			(start 0.120396 0.3048)
			(end 0.120396 0.2794)
			(stroke
				(width 0.1)
				(type default)
			)
			(layer "F.Fab")
		)
		(fp_line
			(start 0.67945 0.3048)
			(end 0.120396 0.3048)
			(stroke
				(width 0.1)
				(type default)
			)
			(layer "F.Fab")
		)
		(fp_line
			(start -0.12065 0.2794)
			(end -0.12065 0.3048)
			(stroke
				(width 0.1)
				(type default)
			)
			(layer "F.Fab")
		)
		(fp_line
			(start 0.120396 0.2794)
			(end -0.12065 0.2794)
			(stroke
				(width 0.1)
				(type default)
			)
			(layer "F.Fab")
		)
		(fp_line
			(start -0.12065 -0.2794)
			(end 0.12065 -0.2794)
			(stroke
				(width 0.1)
				(type default)
			)
			(layer "F.Fab")
		)
		(fp_line
			(start 0.12065 -0.2794)
			(end 0.12065 -0.3048)
			(stroke
				(width 0.1)
				(type default)
			)
			(layer "F.Fab")
		)
		(fp_line
			(start 0.12065 -0.3048)
			(end 0.67945 -0.3048)
			(stroke
				(width 0.1)
				(type default)
			)
			(layer "F.Fab")
		)
		(fp_line
			(start 0.67945 -0.3048)
			(end 0.67945 0.3048)
			(stroke
				(width 0.1)
				(type default)
			)
			(layer "F.Fab")
		)
		(fp_line
			(start -0.67945 -0.305054)
			(end -0.12065 -0.305054)
			(stroke
				(width 0.1)
				(type default)
			)
			(layer "F.Fab")
		)
		(fp_line
			(start -0.12065 -0.305054)
			(end -0.12065 -0.2794)
			(stroke
				(width 0.1)
				(type default)
			)
			(layer "F.Fab")
		)
		(pad "1" smd circle
			(at -0.40005 0 270)
			(size 0 0)
			(layers "F.Cu" "F.Mask" "F.Paste")
			(net "SH_PVCCD_HV_CPU0")
		)
		(pad "2" smd circle
			(at 0.40005 0 270)
			(size 0 0)
			(layers "F.Cu" "F.Mask" "F.Paste")
			(net "SH_PVCCD_HV_CPU0_R")
		)
	)
	(footprint ""
		(layer "F.Cu")
		(at 407.40584 -183.535828)
		(property "Reference" "PC199_P0_1"
			(at 0 0 0)
			(layer "F.SilkS")
			(hide yes)
			(effects
				(font
					(size 1.27 1.27)
				)
			)
		)
		(property "Value" ""
			(at 0 0 0)
			(layer "F.Fab")
			(effects
				(font
					(size 1.27 1.27)
				)
			)
		)
		(duplicate_pad_numbers_are_jumpers no)
		(fp_line
			(start -0.7874 -0.4064)
			(end 0.7874 -0.4064)
			(stroke
				(width 0.1524)
				(type default)
			)
			(layer "F.SilkS")
		)
		(fp_line
			(start -0.7874 0.4064)
			(end -0.7874 -0.4064)
			(stroke
				(width 0.1524)
				(type default)
			)
			(layer "F.SilkS")
		)
		(fp_line
			(start 0.7874 -0.4064)
			(end 0.7874 0.4064)
			(stroke
				(width 0.1524)
				(type default)
			)
			(layer "F.SilkS")
		)
		(fp_line
			(start 0.7874 0.4064)
			(end -0.7874 0.4064)
			(stroke
				(width 0.1524)
				(type default)
			)
			(layer "F.SilkS")
		)
		(fp_line
			(start -0.67945 -0.305054)
			(end -0.12065 -0.305054)
			(stroke
				(width 0.1)
				(type default)
			)
			(layer "F.Fab")
		)
		(fp_line
			(start -0.67945 0.3048)
			(end -0.67945 -0.305054)
			(stroke
				(width 0.1)
				(type default)
			)
			(layer "F.Fab")
		)
		(fp_line
			(start -0.12065 -0.305054)
			(end -0.12065 -0.2794)
			(stroke
				(width 0.1)
				(type default)
			)
			(layer "F.Fab")
		)
		(fp_line
			(start -0.12065 -0.2794)
			(end 0.12065 -0.2794)
			(stroke
				(width 0.1)
				(type default)
			)
			(layer "F.Fab")
		)
		(fp_line
			(start -0.12065 0.2794)
			(end -0.12065 0.3048)
			(stroke
				(width 0.1)
				(type default)
			)
			(layer "F.Fab")
		)
		(fp_line
			(start -0.12065 0.3048)
			(end -0.67945 0.3048)
			(stroke
				(width 0.1)
				(type default)
			)
			(layer "F.Fab")
		)
		(fp_line
			(start 0.120396 0.2794)
			(end -0.12065 0.2794)
			(stroke
				(width 0.1)
				(type default)
			)
			(layer "F.Fab")
		)
		(fp_line
			(start 0.120396 0.3048)
			(end 0.120396 0.2794)
			(stroke
				(width 0.1)
				(type default)
			)
			(layer "F.Fab")
		)
		(fp_line
			(start 0.12065 -0.3048)
			(end 0.67945 -0.3048)
			(stroke
				(width 0.1)
				(type default)
			)
			(layer "F.Fab")
		)
		(fp_line
			(start 0.12065 -0.2794)
			(end 0.12065 -0.3048)
			(stroke
				(width 0.1)
				(type default)
			)
			(layer "F.Fab")
		)
		(fp_line
			(start 0.67945 -0.3048)
			(end 0.67945 0.3048)
			(stroke
				(width 0.1)
				(type default)
			)
			(layer "F.Fab")
		)
		(fp_line
			(start 0.67945 0.3048)
			(end 0.120396 0.3048)
			(stroke
				(width 0.1)
				(type default)
			)
			(layer "F.Fab")
		)
		(pad "1" smd circle
			(at -0.40005 0)
			(size 0 0)
			(layers "F.Cu" "F.Mask" "F.Paste")
			(net "PVCCINFAON_CPU0")
		)
		(pad "2" smd circle
			(at 0.40005 0)
			(size 0 0)
			(layers "F.Cu" "F.Mask" "F.Paste")
			(net "GND")
		)
	)
	(footprint ""
		(layer "F.Cu")
		(at 217.47226 -47.90694 90)
		(property "Reference" "R4767"
			(at 0 0 90)
			(layer "F.SilkS")
			(hide yes)
			(effects
				(font
					(size 1.27 1.27)
				)
			)
		)
		(property "Value" ""
			(at 0 0 90)
			(layer "F.Fab")
			(effects
				(font
					(size 1.27 1.27)
				)
			)
		)
		(duplicate_pad_numbers_are_jumpers no)
		(fp_line
			(start 0.7874 -0.4064)
			(end 0.7874 0.4064)
			(stroke
				(width 0.1524)
				(type default)
			)
			(layer "F.SilkS")
		)
		(fp_line
			(start -0.7874 -0.4064)
			(end 0.7874 -0.4064)
			(stroke
				(width 0.1524)
				(type default)
			)
			(layer "F.SilkS")
		)
		(fp_line
			(start 0.7874 0.4064)
			(end -0.7874 0.4064)
			(stroke
				(width 0.1524)
				(type default)
			)
			(layer "F.SilkS")
		)
		(fp_line
			(start -0.7874 0.4064)
			(end -0.7874 -0.4064)
			(stroke
				(width 0.1524)
				(type default)
			)
			(layer "F.SilkS")
		)
		(fp_line
			(start -0.12065 -0.305054)
			(end -0.12065 -0.2794)
			(stroke
				(width 0.1)
				(type default)
			)
			(layer "F.Fab")
		)
		(fp_line
			(start -0.67945 -0.305054)
			(end -0.12065 -0.305054)
			(stroke
				(width 0.1)
				(type default)
			)
			(layer "F.Fab")
		)
		(fp_line
			(start 0.67945 -0.3048)
			(end 0.67945 0.3048)
			(stroke
				(width 0.1)
				(type default)
			)
			(layer "F.Fab")
		)
		(fp_line
			(start 0.12065 -0.3048)
			(end 0.67945 -0.3048)
			(stroke
				(width 0.1)
				(type default)
			)
			(layer "F.Fab")
		)
		(fp_line
			(start 0.12065 -0.2794)
			(end 0.12065 -0.3048)
			(stroke
				(width 0.1)
				(type default)
			)
			(layer "F.Fab")
		)
		(fp_line
			(start -0.12065 -0.2794)
			(end 0.12065 -0.2794)
			(stroke
				(width 0.1)
				(type default)
			)
			(layer "F.Fab")
		)
		(fp_line
			(start 0.120396 0.2794)
			(end -0.12065 0.2794)
			(stroke
				(width 0.1)
				(type default)
			)
			(layer "F.Fab")
		)
		(fp_line
			(start -0.12065 0.2794)
			(end -0.12065 0.3048)
			(stroke
				(width 0.1)
				(type default)
			)
			(layer "F.Fab")
		)
		(fp_line
			(start 0.67945 0.3048)
			(end 0.120396 0.3048)
			(stroke
				(width 0.1)
				(type default)
			)
			(layer "F.Fab")
		)
		(fp_line
			(start 0.120396 0.3048)
			(end 0.120396 0.2794)
			(stroke
				(width 0.1)
				(type default)
			)
			(layer "F.Fab")
		)
		(fp_line
			(start -0.12065 0.3048)
			(end -0.67945 0.3048)
			(stroke
				(width 0.1)
				(type default)
			)
			(layer "F.Fab")
		)
		(fp_line
			(start -0.67945 0.3048)
			(end -0.67945 -0.305054)
			(stroke
				(width 0.1)
				(type default)
			)
			(layer "F.Fab")
		)
		(pad "1" smd circle
			(at -0.40005 0 90)
			(size 0 0)
			(layers "F.Cu" "F.Mask" "F.Paste")
			(net "HP_E1S_0_P3V3_PWRGD")
		)
		(pad "2" smd circle
			(at 0.40005 0 90)
			(size 0 0)
			(layers "F.Cu" "F.Mask" "F.Paste")
			(net "HP_E1S_0_P3V3_PWRGD_PLD")
		)
	)
	(footprint ""
		(layer "F.Cu")
		(at 369.554252 -366.764062 -90)
		(property "Reference" "PC1254"
			(at 0 0 270)
			(layer "F.SilkS")
			(hide yes)
			(effects
				(font
					(size 1.27 1.27)
				)
			)
		)
		(property "Value" ""
			(at 0 0 270)
			(layer "F.Fab")
			(effects
				(font
					(size 1.27 1.27)
				)
			)
		)
		(duplicate_pad_numbers_are_jumpers no)
		(fp_line
			(start -0.7874 0.4064)
			(end -0.7874 -0.4064)
			(stroke
				(width 0.1524)
				(type default)
			)
			(layer "F.SilkS")
		)
		(fp_line
			(start 0.7874 0.4064)
			(end -0.7874 0.4064)
			(stroke
				(width 0.1524)
				(type default)
			)
			(layer "F.SilkS")
		)
		(fp_line
			(start -0.7874 -0.4064)
			(end 0.7874 -0.4064)
			(stroke
				(width 0.1524)
				(type default)
			)
			(layer "F.SilkS")
		)
		(fp_line
			(start 0.7874 -0.4064)
			(end 0.7874 0.4064)
			(stroke
				(width 0.1524)
				(type default)
			)
			(layer "F.SilkS")
		)
		(fp_line
			(start -0.67945 0.3048)
			(end -0.67945 -0.305054)
			(stroke
				(width 0.1)
				(type default)
			)
			(layer "F.Fab")
		)
		(fp_line
			(start -0.12065 0.3048)
			(end -0.67945 0.3048)
			(stroke
				(width 0.1)
				(type default)
			)
			(layer "F.Fab")
		)
		(fp_line
			(start 0.120396 0.3048)
			(end 0.120396 0.2794)
			(stroke
				(width 0.1)
				(type default)
			)
			(layer "F.Fab")
		)
		(fp_line
			(start 0.67945 0.3048)
			(end 0.120396 0.3048)
			(stroke
				(width 0.1)
				(type default)
			)
			(layer "F.Fab")
		)
		(fp_line
			(start -0.12065 0.2794)
			(end -0.12065 0.3048)
			(stroke
				(width 0.1)
				(type default)
			)
			(layer "F.Fab")
		)
		(fp_line
			(start 0.120396 0.2794)
			(end -0.12065 0.2794)
			(stroke
				(width 0.1)
				(type default)
			)
			(layer "F.Fab")
		)
		(fp_line
			(start -0.12065 -0.2794)
			(end 0.12065 -0.2794)
			(stroke
				(width 0.1)
				(type default)
			)
			(layer "F.Fab")
		)
		(fp_line
			(start 0.12065 -0.2794)
			(end 0.12065 -0.3048)
			(stroke
				(width 0.1)
				(type default)
			)
			(layer "F.Fab")
		)
		(fp_line
			(start 0.12065 -0.3048)
			(end 0.67945 -0.3048)
			(stroke
				(width 0.1)
				(type default)
			)
			(layer "F.Fab")
		)
		(fp_line
			(start 0.67945 -0.3048)
			(end 0.67945 0.3048)
			(stroke
				(width 0.1)
				(type default)
			)
			(layer "F.Fab")
		)
		(fp_line
			(start -0.67945 -0.305054)
			(end -0.12065 -0.305054)
			(stroke
				(width 0.1)
				(type default)
			)
			(layer "F.Fab")
		)
		(fp_line
			(start -0.12065 -0.305054)
			(end -0.12065 -0.2794)
			(stroke
				(width 0.1)
				(type default)
			)
			(layer "F.Fab")
		)
		(pad "1" smd circle
			(at -0.40005 0 270)
			(size 0 0)
			(layers "F.Cu" "F.Mask" "F.Paste")
			(net "PVPP_HBM_CPU0")
		)
		(pad "2" smd circle
			(at 0.40005 0 270)
			(size 0 0)
			(layers "F.Cu" "F.Mask" "F.Paste")
			(net "GND")
		)
	)
)
